(kicad_pcb
	(version 20260206)
	(generator "pcbnew")
	(generator_version "10.0")
	(general
		(thickness 1.6)
		(legacy_teardrops no)
	)
	(paper "A4")
	(title_block
		(title "12092022_DA0F0TMDCD0_F0T_Management_Board_D_brd_V3_OCP.brd")
		(comment 1 "Grand Teton / footprints 197-200 of 1440")
	)
	(layers
		(0 "F.Cu" signal "TOP")
		(4 "In1.Cu" signal "GND")
		(6 "In2.Cu" signal "IN1")
		(8 "In3.Cu" signal "GND1")
		(10 "In4.Cu" signal "IN2")
		(12 "In5.Cu" signal "VCC")
		(14 "In6.Cu" signal "VCC1")
		(16 "In7.Cu" signal "IN3")
		(18 "In8.Cu" signal "GND2")
		(20 "In9.Cu" signal "IN4")
		(22 "In10.Cu" signal "GND3")
		(2 "B.Cu" signal "BOTTOM")
		(9 "F.Adhes" user "F.Adhesive")
		(11 "B.Adhes" user "B.Adhesive")
		(13 "F.Paste" user "Package Geometry/Pastemask Top")
		(15 "B.Paste" user "Package Geometry/Pastemask Bottom")
		(5 "F.SilkS" user "Ref Des/Silkscreen Top")
		(7 "B.SilkS" user "Ref Des/Silkscreen Bottom")
		(1 "F.Mask" user "Board Geometry/Soldermask Top")
		(3 "B.Mask" user "Board Geometry/Soldermask Bottom")
		(17 "Dwgs.User" user "User.Drawings")
		(19 "Cmts.User" user "User.Comments")
		(21 "Eco1.User" user "User.Eco1")
		(23 "Eco2.User" user "User.Eco2")
		(25 "Edge.Cuts" user "Board Geometry/Outline")
		(27 "Margin" user)
		(31 "F.CrtYd" user "Package Geometry/Place Bound Top")
		(29 "B.CrtYd" user "Package Geometry/Place Bound Bottom")
		(35 "F.Fab" user "Ref Des/Assembly Top")
		(33 "B.Fab" user "Ref Des/Assembly Bottom")
	)
	(footprint ""
		(layer "F.Cu")
		(at 46.736 -34.6456 90)
		(property "Reference" "R763"
			(at 0 0 90)
			(layer "F.SilkS")
			(hide yes)
			(effects
				(font
					(size 1.27 1.27)
				)
			)
		)
		(property "Value" ""
			(at 0 0 90)
			(layer "F.Fab")
			(effects
				(font
					(size 1.27 1.27)
				)
			)
		)
		(duplicate_pad_numbers_are_jumpers no)
		(fp_line
			(start 0.7874 -0.4064)
			(end 0.7874 0.4064)
			(stroke
				(width 0.1524)
				(type default)
			)
			(layer "F.SilkS")
		)
		(fp_line
			(start -0.7874 -0.4064)
			(end 0.7874 -0.4064)
			(stroke
				(width 0.1524)
				(type default)
			)
			(layer "F.SilkS")
		)
		(fp_line
			(start 0.7874 0.4064)
			(end -0.7874 0.4064)
			(stroke
				(width 0.1524)
				(type default)
			)
			(layer "F.SilkS")
		)
		(fp_line
			(start -0.7874 0.4064)
			(end -0.7874 -0.4064)
			(stroke
				(width 0.1524)
				(type default)
			)
			(layer "F.SilkS")
		)
		(fp_line
			(start -0.12065 -0.305054)
			(end -0.12065 -0.2794)
			(stroke
				(width 0.1)
				(type default)
			)
			(layer "F.Fab")
		)
		(fp_line
			(start -0.67945 -0.305054)
			(end -0.12065 -0.305054)
			(stroke
				(width 0.1)
				(type default)
			)
			(layer "F.Fab")
		)
		(fp_line
			(start 0.67945 -0.3048)
			(end 0.67945 0.3048)
			(stroke
				(width 0.1)
				(type default)
			)
			(layer "F.Fab")
		)
		(fp_line
			(start 0.12065 -0.3048)
			(end 0.67945 -0.3048)
			(stroke
				(width 0.1)
				(type default)
			)
			(layer "F.Fab")
		)
		(fp_line
			(start 0.12065 -0.2794)
			(end 0.12065 -0.3048)
			(stroke
				(width 0.1)
				(type default)
			)
			(layer "F.Fab")
		)
		(fp_line
			(start -0.12065 -0.2794)
			(end 0.12065 -0.2794)
			(stroke
				(width 0.1)
				(type default)
			)
			(layer "F.Fab")
		)
		(fp_line
			(start 0.120396 0.2794)
			(end -0.12065 0.2794)
			(stroke
				(width 0.1)
				(type default)
			)
			(layer "F.Fab")
		)
		(fp_line
			(start -0.12065 0.2794)
			(end -0.12065 0.3048)
			(stroke
				(width 0.1)
				(type default)
			)
			(layer "F.Fab")
		)
		(fp_line
			(start 0.67945 0.3048)
			(end 0.120396 0.3048)
			(stroke
				(width 0.1)
				(type default)
			)
			(layer "F.Fab")
		)
		(fp_line
			(start 0.120396 0.3048)
			(end 0.120396 0.2794)
			(stroke
				(width 0.1)
				(type default)
			)
			(layer "F.Fab")
		)
		(fp_line
			(start -0.12065 0.3048)
			(end -0.67945 0.3048)
			(stroke
				(width 0.1)
				(type default)
			)
			(layer "F.Fab")
		)
		(fp_line
			(start -0.67945 0.3048)
			(end -0.67945 -0.305054)
			(stroke
				(width 0.1)
				(type default)
			)
			(layer "F.Fab")
		)
		(pad "1" smd circle
			(at -0.40005 0 90)
			(size 0 0)
			(layers "F.Cu" "F.Mask" "F.Paste")
			(net "FM_PCH_BMC_THERMTRIP_N")
		)
		(pad "2" smd circle
			(at 0.40005 0 90)
			(size 0 0)
			(layers "F.Cu" "F.Mask" "F.Paste")
			(net "FM_PLT_BMC_THERMTRIP_N_R")
		)
	)
	(footprint ""
		(layer "F.Cu")
		(at 26.750264 -54.189122)
		(property "Reference" "H1"
			(at -1.7272 -4.511548 0)
			(unlocked yes)
			(layer "B.SilkS")
			(effects
				(font
					(size 0.7874 0.5842)
					(thickness 0.1524)
				)
				(justify left mirror)
			)
		)
		(property "Value" ""
			(at 0 0 0)
			(layer "F.Fab")
			(effects
				(font
					(size 1.27 1.27)
				)
			)
		)
		(duplicate_pad_numbers_are_jumpers no)
		(pad "1" thru_hole circle
			(at 0 0)
			(size 4.5212 4.5212)
			(drill 3.81)
			(layers "*.Cu" "*.Mask")
			(remove_unused_layers no)
			(net "GND")
			(clearance -0.1016)
			(padstack
				(mode front_inner_back)
				(layer "Inner"
					(shape circle)
					(size 5.6134 5.6134)
					(clearance -0.6477)
				)
				(layer "B.Cu"
					(shape circle)
					(size 8.001 8.001)
					(clearance -1.8415)
				)
			)
		)
	)
	(footprint ""
		(layer "F.Cu")
		(at 6.858 -57.404)
		(property "Reference" "PL4"
			(at 0 0 0)
			(layer "F.SilkS")
			(hide yes)
			(effects
				(font
					(size 1.27 1.27)
				)
			)
		)
		(property "Value" ""
			(at 0 0 0)
			(layer "F.Fab")
			(effects
				(font
					(size 1.27 1.27)
				)
			)
		)
		(duplicate_pad_numbers_are_jumpers no)
		(fp_line
			(start -1.27 -0.5842)
			(end 1.27 -0.5842)
			(stroke
				(width 0.1524)
				(type default)
			)
			(layer "F.SilkS")
		)
		(fp_line
			(start -1.27 -0.5588)
			(end -1.27 -0.5842)
			(stroke
				(width 0.1524)
				(type default)
			)
			(layer "F.SilkS")
		)
		(fp_line
			(start -1.27 0.5842)
			(end -1.27 -0.5842)
			(stroke
				(width 0.1524)
				(type default)
			)
			(layer "F.SilkS")
		)
		(fp_line
			(start -0.127 0.5842)
			(end -0.127 -0.5842)
			(stroke
				(width 0.1524)
				(type default)
			)
			(layer "F.SilkS")
		)
		(fp_line
			(start 0.127 0.5842)
			(end 0.127 -0.5842)
			(stroke
				(width 0.1524)
				(type default)
			)
			(layer "F.SilkS")
		)
		(fp_line
			(start 1.27 0.5842)
			(end -1.27 0.5842)
			(stroke
				(width 0.1524)
				(type default)
			)
			(layer "F.SilkS")
		)
		(fp_line
			(start 1.27 0.5842)
			(end 1.27 -0.5842)
			(stroke
				(width 0.1524)
				(type default)
			)
			(layer "F.SilkS")
		)
		(fp_line
			(start -1.194308 -0.406654)
			(end -0.9144 -0.406654)
			(stroke
				(width 0.1)
				(type default)
			)
			(layer "F.Fab")
		)
		(fp_line
			(start -1.194308 0.406654)
			(end -1.194308 -0.406654)
			(stroke
				(width 0.1)
				(type default)
			)
			(layer "F.Fab")
		)
		(fp_line
			(start -0.9144 -0.508)
			(end 0.9144 -0.508)
			(stroke
				(width 0.1)
				(type default)
			)
			(layer "F.Fab")
		)
		(fp_line
			(start -0.9144 -0.406654)
			(end -0.9144 -0.508)
			(stroke
				(width 0.1)
				(type default)
			)
			(layer "F.Fab")
		)
		(fp_line
			(start -0.9144 0.406654)
			(end -1.194308 0.406654)
			(stroke
				(width 0.1)
				(type default)
			)
			(layer "F.Fab")
		)
		(fp_line
			(start -0.9144 0.508)
			(end -0.9144 0.406654)
			(stroke
				(width 0.1)
				(type default)
			)
			(layer "F.Fab")
		)
		(fp_line
			(start 0.9144 -0.508)
			(end 0.9144 -0.406654)
			(stroke
				(width 0.1)
				(type default)
			)
			(layer "F.Fab")
		)
		(fp_line
			(start 0.9144 -0.406654)
			(end 1.1938 -0.406654)
			(stroke
				(width 0.1)
				(type default)
			)
			(layer "F.Fab")
		)
		(fp_line
			(start 0.9144 0.4064)
			(end 0.9144 0.508)
			(stroke
				(width 0.1)
				(type default)
			)
			(layer "F.Fab")
		)
		(fp_line
			(start 0.9144 0.508)
			(end -0.9144 0.508)
			(stroke
				(width 0.1)
				(type default)
			)
			(layer "F.Fab")
		)
		(fp_line
			(start 1.1938 -0.406654)
			(end 1.1938 0.4064)
			(stroke
				(width 0.1)
				(type default)
			)
			(layer "F.Fab")
		)
		(fp_line
			(start 1.1938 0.4064)
			(end 0.9144 0.4064)
			(stroke
				(width 0.1)
				(type default)
			)
			(layer "F.Fab")
		)
		(pad "1" smd rect
			(at -0.7366 0 270)
			(size 0.7112 0.8128)
			(layers "F.Cu" "F.Mask" "F.Paste")
			(net "P12V_AUX")
		)
		(pad "2" smd rect
			(at 0.7366 0 270)
			(size 0.7112 0.8128)
			(layers "F.Cu" "F.Mask" "F.Paste")
			(net "SW_P5V_AUX_FLT")
		)
	)
	(footprint ""
		(layer "F.Cu")
		(at 7.112 -31.837122 -90)
		(property "Reference" "PC213"
			(at 0 0 270)
			(layer "F.SilkS")
			(hide yes)
			(effects
				(font
					(size 1.27 1.27)
				)
			)
		)
		(property "Value" ""
			(at 0 0 270)
			(layer "F.Fab")
			(effects
				(font
					(size 1.27 1.27)
				)
			)
		)
		(duplicate_pad_numbers_are_jumpers no)
		(fp_line
			(start -1.651 0.8382)
			(end -1.651 -0.8382)
			(stroke
				(width 0.1524)
				(type default)
			)
			(layer "F.SilkS")
		)
		(fp_line
			(start 0 0.8382)
			(end 0 -0.8382)
			(stroke
				(width 0.1524)
				(type default)
			)
			(layer "F.SilkS")
		)
		(fp_line
			(start 1.651 0.8382)
			(end -1.651 0.8382)
			(stroke
				(width 0.1524)
				(type default)
			)
			(layer "F.SilkS")
		)
		(fp_line
			(start -1.651 -0.8382)
			(end 1.651 -0.8382)
			(stroke
				(width 0.1524)
				(type default)
			)
			(layer "F.SilkS")
		)
		(fp_line
			(start 1.651 -0.8382)
			(end 1.651 0.8382)
			(stroke
				(width 0.1524)
				(type default)
			)
			(layer "F.SilkS")
		)
		(fp_line
			(start -1.55956 0.7366)
			(end -1.524 0.7366)
			(stroke
				(width 0.1)
				(type default)
			)
			(layer "F.Fab")
		)
		(fp_line
			(start -1.524 0.7366)
			(end 1.524 0.7366)
			(stroke
				(width 0.1)
				(type default)
			)
			(layer "F.Fab")
		)
		(fp_line
			(start 1.524 0.7366)
			(end 1.55956 0.7366)
			(stroke
				(width 0.1)
				(type default)
			)
			(layer "F.Fab")
		)
		(fp_line
			(start 1.55956 0.7366)
			(end 1.55956 -0.7366)
			(stroke
				(width 0.1)
				(type default)
			)
			(layer "F.Fab")
		)
		(fp_line
			(start -1.55956 -0.7366)
			(end -1.55956 0.7366)
			(stroke
				(width 0.1)
				(type default)
			)
			(layer "F.Fab")
		)
		(fp_line
			(start -1.524 -0.7366)
			(end -1.55956 -0.7366)
			(stroke
				(width 0.1)
				(type default)
			)
			(layer "F.Fab")
		)
		(fp_line
			(start 1.524 -0.7366)
			(end -1.524 -0.7366)
			(stroke
				(width 0.1)
				(type default)
			)
			(layer "F.Fab")
		)
		(fp_line
			(start 1.55956 -0.7366)
			(end 1.524 -0.7366)
			(stroke
				(width 0.1)
				(type default)
			)
			(layer "F.Fab")
		)
		(pad "1" smd rect
			(at -0.94996 0 90)
			(size 1.1176 1.3716)
			(layers "F.Cu" "F.Mask" "F.Paste")
			(net "P5V_AUX")
		)
		(pad "2" smd rect
			(at 0.94996 0 90)
			(size 1.1176 1.3716)
			(layers "F.Cu" "F.Mask" "F.Paste")
			(net "GND")
		)
	)
)
